(kicad_pcb
	(version 20260206)
	(generator "pcbnew")
	(generator_version "10.0")
	(general
		(thickness 1.6)
		(legacy_teardrops no)
	)
	(paper "A4")
	(title_block
		(title "04192023_DAF0TMB3IC0_F0TG_MB_C_brd_V02_OCP.brd")
		(comment 1 "Grand Teton / footprints 65-71 of 8354")
	)
	(layers
		(0 "F.Cu" signal "TOP")
		(4 "In1.Cu" signal "GND")
		(6 "In2.Cu" signal "IN1")
		(8 "In3.Cu" signal "GND1")
		(10 "In4.Cu" signal "IN2")
		(12 "In5.Cu" signal "GND2")
		(14 "In6.Cu" signal "IN3")
		(16 "In7.Cu" signal "GND3")
		(18 "In8.Cu" signal "VCC")
		(20 "In9.Cu" signal "VCC1")
		(22 "In10.Cu" signal "GND4")
		(24 "In11.Cu" signal "IN4")
		(26 "In12.Cu" signal "GND5")
		(28 "In13.Cu" signal "IN5")
		(30 "In14.Cu" signal "GND6")
		(32 "In15.Cu" signal "IN6")
		(34 "In16.Cu" signal "GND7")
		(2 "B.Cu" signal "BOTTOM")
		(9 "F.Adhes" user "F.Adhesive")
		(11 "B.Adhes" user "B.Adhesive")
		(13 "F.Paste" user "Package Geometry/Pastemask Top")
		(15 "B.Paste" user "Package Geometry/Pastemask Bottom")
		(5 "F.SilkS" user "Ref Des/Silkscreen Top")
		(7 "B.SilkS" user "Ref Des/Silkscreen Bottom")
		(1 "F.Mask" user "Board Geometry/Soldermask Top")
		(3 "B.Mask" user "Board Geometry/Soldermask Bottom")
		(17 "Dwgs.User" user "User.Drawings")
		(19 "Cmts.User" user "User.Comments")
		(21 "Eco1.User" user "User.Eco1")
		(23 "Eco2.User" user "User.Eco2")
		(25 "Edge.Cuts" user "Board Geometry/Outline")
		(27 "Margin" user)
		(31 "F.CrtYd" user "Package Geometry/Place Bound Top")
		(29 "B.CrtYd" user "Package Geometry/Place Bound Bottom")
		(35 "F.Fab" user "Ref Des/Assembly Top")
		(33 "B.Fab" user "Ref Des/Assembly Bottom")
	)
	(footprint ""
		(layer "F.Cu")
		(at 145.669 -118.364)
		(property "Reference" "C8021"
			(at 0 0 0)
			(layer "F.SilkS")
			(hide yes)
			(effects
				(font
					(size 1.27 1.27)
				)
			)
		)
		(property "Value" ""
			(at 0 0 0)
			(layer "F.Fab")
			(effects
				(font
					(size 1.27 1.27)
				)
			)
		)
		(duplicate_pad_numbers_are_jumpers no)
		(fp_line
			(start -0.7874 -0.4064)
			(end 0.7874 -0.4064)
			(stroke
				(width 0.1524)
				(type default)
			)
			(layer "F.SilkS")
		)
		(fp_line
			(start -0.7874 0.4064)
			(end -0.7874 -0.4064)
			(stroke
				(width 0.1524)
				(type default)
			)
			(layer "F.SilkS")
		)
		(fp_line
			(start 0.7874 -0.4064)
			(end 0.7874 0.4064)
			(stroke
				(width 0.1524)
				(type default)
			)
			(layer "F.SilkS")
		)
		(fp_line
			(start 0.7874 0.4064)
			(end -0.7874 0.4064)
			(stroke
				(width 0.1524)
				(type default)
			)
			(layer "F.SilkS")
		)
		(fp_line
			(start -0.67945 -0.305054)
			(end -0.12065 -0.305054)
			(stroke
				(width 0.1)
				(type default)
			)
			(layer "F.Fab")
		)
		(fp_line
			(start -0.67945 0.3048)
			(end -0.67945 -0.305054)
			(stroke
				(width 0.1)
				(type default)
			)
			(layer "F.Fab")
		)
		(fp_line
			(start -0.12065 -0.305054)
			(end -0.12065 -0.2794)
			(stroke
				(width 0.1)
				(type default)
			)
			(layer "F.Fab")
		)
		(fp_line
			(start -0.12065 -0.2794)
			(end 0.12065 -0.2794)
			(stroke
				(width 0.1)
				(type default)
			)
			(layer "F.Fab")
		)
		(fp_line
			(start -0.12065 0.2794)
			(end -0.12065 0.3048)
			(stroke
				(width 0.1)
				(type default)
			)
			(layer "F.Fab")
		)
		(fp_line
			(start -0.12065 0.3048)
			(end -0.67945 0.3048)
			(stroke
				(width 0.1)
				(type default)
			)
			(layer "F.Fab")
		)
		(fp_line
			(start 0.120396 0.2794)
			(end -0.12065 0.2794)
			(stroke
				(width 0.1)
				(type default)
			)
			(layer "F.Fab")
		)
		(fp_line
			(start 0.120396 0.3048)
			(end 0.120396 0.2794)
			(stroke
				(width 0.1)
				(type default)
			)
			(layer "F.Fab")
		)
		(fp_line
			(start 0.12065 -0.3048)
			(end 0.67945 -0.3048)
			(stroke
				(width 0.1)
				(type default)
			)
			(layer "F.Fab")
		)
		(fp_line
			(start 0.12065 -0.2794)
			(end 0.12065 -0.3048)
			(stroke
				(width 0.1)
				(type default)
			)
			(layer "F.Fab")
		)
		(fp_line
			(start 0.67945 -0.3048)
			(end 0.67945 0.3048)
			(stroke
				(width 0.1)
				(type default)
			)
			(layer "F.Fab")
		)
		(fp_line
			(start 0.67945 0.3048)
			(end 0.120396 0.3048)
			(stroke
				(width 0.1)
				(type default)
			)
			(layer "F.Fab")
		)
		(pad "1" smd circle
			(at -0.40005 0)
			(size 0 0)
			(layers "F.Cu" "F.Mask" "F.Paste")
			(net "P12V_AUX_UV_TRIGGER")
		)
		(pad "2" smd circle
			(at 0.40005 0)
			(size 0 0)
			(layers "F.Cu" "F.Mask" "F.Paste")
			(net "GND")
		)
	)
	(footprint ""
		(layer "F.Cu")
		(at 424.609006 -402.7424 -90)
		(property "Reference" "R1084"
			(at 0 0 270)
			(layer "F.SilkS")
			(hide yes)
			(effects
				(font
					(size 1.27 1.27)
				)
			)
		)
		(property "Value" ""
			(at 0 0 270)
			(layer "F.Fab")
			(effects
				(font
					(size 1.27 1.27)
				)
			)
		)
		(duplicate_pad_numbers_are_jumpers no)
		(fp_line
			(start -0.32512 0.175006)
			(end -0.32512 -0.175006)
			(stroke
				(width 0.1)
				(type default)
			)
			(layer "F.Fab")
		)
		(fp_line
			(start 0.32512 0.175006)
			(end -0.32512 0.175006)
			(stroke
				(width 0.1)
				(type default)
			)
			(layer "F.Fab")
		)
		(fp_line
			(start -0.32512 -0.175006)
			(end 0.32512 -0.175006)
			(stroke
				(width 0.1)
				(type default)
			)
			(layer "F.Fab")
		)
		(fp_line
			(start 0.32512 -0.175006)
			(end 0.32512 0.175006)
			(stroke
				(width 0.1)
				(type default)
			)
			(layer "F.Fab")
		)
		(pad "1" smd rect
			(at -0.2667 0 270)
			(size 0.3048 0.381)
			(layers "F.Cu" "F.Mask" "F.Paste")
			(net "NCF_A1_CPU0_P2_GND")
		)
		(pad "2" smd rect
			(at 0.2667 0 90)
			(size 0.3048 0.381)
			(layers "F.Cu" "F.Mask" "F.Paste")
			(net "GND")
		)
	)
	(footprint ""
		(layer "F.Cu")
		(at 219.276676 -67.954144 -90)
		(property "Reference" "PR3964"
			(at 0 0 270)
			(layer "F.SilkS")
			(hide yes)
			(effects
				(font
					(size 1.27 1.27)
				)
			)
		)
		(property "Value" ""
			(at 0 0 270)
			(layer "F.Fab")
			(effects
				(font
					(size 1.27 1.27)
				)
			)
		)
		(duplicate_pad_numbers_are_jumpers no)
		(fp_line
			(start -0.7874 0.4064)
			(end -0.7874 -0.4064)
			(stroke
				(width 0.1524)
				(type default)
			)
			(layer "F.SilkS")
		)
		(fp_line
			(start 0.7874 0.4064)
			(end -0.7874 0.4064)
			(stroke
				(width 0.1524)
				(type default)
			)
			(layer "F.SilkS")
		)
		(fp_line
			(start -0.7874 -0.4064)
			(end 0.7874 -0.4064)
			(stroke
				(width 0.1524)
				(type default)
			)
			(layer "F.SilkS")
		)
		(fp_line
			(start 0.7874 -0.4064)
			(end 0.7874 0.4064)
			(stroke
				(width 0.1524)
				(type default)
			)
			(layer "F.SilkS")
		)
		(fp_line
			(start -0.67945 0.3048)
			(end -0.67945 -0.305054)
			(stroke
				(width 0.1)
				(type default)
			)
			(layer "F.Fab")
		)
		(fp_line
			(start -0.12065 0.3048)
			(end -0.67945 0.3048)
			(stroke
				(width 0.1)
				(type default)
			)
			(layer "F.Fab")
		)
		(fp_line
			(start 0.120396 0.3048)
			(end 0.120396 0.2794)
			(stroke
				(width 0.1)
				(type default)
			)
			(layer "F.Fab")
		)
		(fp_line
			(start 0.67945 0.3048)
			(end 0.120396 0.3048)
			(stroke
				(width 0.1)
				(type default)
			)
			(layer "F.Fab")
		)
		(fp_line
			(start -0.12065 0.2794)
			(end -0.12065 0.3048)
			(stroke
				(width 0.1)
				(type default)
			)
			(layer "F.Fab")
		)
		(fp_line
			(start 0.120396 0.2794)
			(end -0.12065 0.2794)
			(stroke
				(width 0.1)
				(type default)
			)
			(layer "F.Fab")
		)
		(fp_line
			(start -0.12065 -0.2794)
			(end 0.12065 -0.2794)
			(stroke
				(width 0.1)
				(type default)
			)
			(layer "F.Fab")
		)
		(fp_line
			(start 0.12065 -0.2794)
			(end 0.12065 -0.3048)
			(stroke
				(width 0.1)
				(type default)
			)
			(layer "F.Fab")
		)
		(fp_line
			(start 0.12065 -0.3048)
			(end 0.67945 -0.3048)
			(stroke
				(width 0.1)
				(type default)
			)
			(layer "F.Fab")
		)
		(fp_line
			(start 0.67945 -0.3048)
			(end 0.67945 0.3048)
			(stroke
				(width 0.1)
				(type default)
			)
			(layer "F.Fab")
		)
		(fp_line
			(start -0.67945 -0.305054)
			(end -0.12065 -0.305054)
			(stroke
				(width 0.1)
				(type default)
			)
			(layer "F.Fab")
		)
		(fp_line
			(start -0.12065 -0.305054)
			(end -0.12065 -0.2794)
			(stroke
				(width 0.1)
				(type default)
			)
			(layer "F.Fab")
		)
		(pad "1" smd circle
			(at -0.40005 0 270)
			(size 0 0)
			(layers "F.Cu" "F.Mask" "F.Paste")
			(net "P3V3_E1S_UV_0")
		)
		(pad "2" smd circle
			(at 0.40005 0 270)
			(size 0 0)
			(layers "F.Cu" "F.Mask" "F.Paste")
			(net "P3V3_E1S_OV_0")
		)
	)
	(footprint ""
		(layer "F.Cu")
		(at 205.243684 -120.944386)
		(property "Reference" "R4144"
			(at 0 0 0)
			(layer "F.SilkS")
			(hide yes)
			(effects
				(font
					(size 1.27 1.27)
				)
			)
		)
		(property "Value" ""
			(at 0 0 0)
			(layer "F.Fab")
			(effects
				(font
					(size 1.27 1.27)
				)
			)
		)
		(duplicate_pad_numbers_are_jumpers no)
		(fp_line
			(start -0.7874 -0.4064)
			(end 0.7874 -0.4064)
			(stroke
				(width 0.1524)
				(type default)
			)
			(layer "F.SilkS")
		)
		(fp_line
			(start -0.7874 0.4064)
			(end -0.7874 -0.4064)
			(stroke
				(width 0.1524)
				(type default)
			)
			(layer "F.SilkS")
		)
		(fp_line
			(start 0.7874 -0.4064)
			(end 0.7874 0.4064)
			(stroke
				(width 0.1524)
				(type default)
			)
			(layer "F.SilkS")
		)
		(fp_line
			(start 0.7874 0.4064)
			(end -0.7874 0.4064)
			(stroke
				(width 0.1524)
				(type default)
			)
			(layer "F.SilkS")
		)
		(fp_line
			(start -0.67945 -0.305054)
			(end -0.12065 -0.305054)
			(stroke
				(width 0.1)
				(type default)
			)
			(layer "F.Fab")
		)
		(fp_line
			(start -0.67945 0.3048)
			(end -0.67945 -0.305054)
			(stroke
				(width 0.1)
				(type default)
			)
			(layer "F.Fab")
		)
		(fp_line
			(start -0.12065 -0.305054)
			(end -0.12065 -0.2794)
			(stroke
				(width 0.1)
				(type default)
			)
			(layer "F.Fab")
		)
		(fp_line
			(start -0.12065 -0.2794)
			(end 0.12065 -0.2794)
			(stroke
				(width 0.1)
				(type default)
			)
			(layer "F.Fab")
		)
		(fp_line
			(start -0.12065 0.2794)
			(end -0.12065 0.3048)
			(stroke
				(width 0.1)
				(type default)
			)
			(layer "F.Fab")
		)
		(fp_line
			(start -0.12065 0.3048)
			(end -0.67945 0.3048)
			(stroke
				(width 0.1)
				(type default)
			)
			(layer "F.Fab")
		)
		(fp_line
			(start 0.120396 0.2794)
			(end -0.12065 0.2794)
			(stroke
				(width 0.1)
				(type default)
			)
			(layer "F.Fab")
		)
		(fp_line
			(start 0.120396 0.3048)
			(end 0.120396 0.2794)
			(stroke
				(width 0.1)
				(type default)
			)
			(layer "F.Fab")
		)
		(fp_line
			(start 0.12065 -0.3048)
			(end 0.67945 -0.3048)
			(stroke
				(width 0.1)
				(type default)
			)
			(layer "F.Fab")
		)
		(fp_line
			(start 0.12065 -0.2794)
			(end 0.12065 -0.3048)
			(stroke
				(width 0.1)
				(type default)
			)
			(layer "F.Fab")
		)
		(fp_line
			(start 0.67945 -0.3048)
			(end 0.67945 0.3048)
			(stroke
				(width 0.1)
				(type default)
			)
			(layer "F.Fab")
		)
		(fp_line
			(start 0.67945 0.3048)
			(end 0.120396 0.3048)
			(stroke
				(width 0.1)
				(type default)
			)
			(layer "F.Fab")
		)
		(pad "1" smd circle
			(at -0.40005 0)
			(size 0 0)
			(layers "F.Cu" "F.Mask" "F.Paste")
			(net "GPU_3V3IO_RSVD1_FFU_ISO_R")
		)
		(pad "2" smd circle
			(at 0.40005 0)
			(size 0 0)
			(layers "F.Cu" "F.Mask" "F.Paste")
			(net "GPU_3V3IO_RSVD1_FFU_ISO")
		)
	)
	(footprint ""
		(layer "F.Cu")
		(at 331.381862 -333.239364 90)
		(property "Reference" "PR506"
			(at 0 0 90)
			(layer "F.SilkS")
			(hide yes)
			(effects
				(font
					(size 1.27 1.27)
				)
			)
		)
		(property "Value" ""
			(at 0 0 90)
			(layer "F.Fab")
			(effects
				(font
					(size 1.27 1.27)
				)
			)
		)
		(duplicate_pad_numbers_are_jumpers no)
		(fp_line
			(start 0.7874 -0.4064)
			(end 0.7874 0.4064)
			(stroke
				(width 0.1524)
				(type default)
			)
			(layer "F.SilkS")
		)
		(fp_line
			(start -0.7874 -0.4064)
			(end 0.7874 -0.4064)
			(stroke
				(width 0.1524)
				(type default)
			)
			(layer "F.SilkS")
		)
		(fp_line
			(start 0.7874 0.4064)
			(end -0.7874 0.4064)
			(stroke
				(width 0.1524)
				(type default)
			)
			(layer "F.SilkS")
		)
		(fp_line
			(start -0.7874 0.4064)
			(end -0.7874 -0.4064)
			(stroke
				(width 0.1524)
				(type default)
			)
			(layer "F.SilkS")
		)
		(fp_line
			(start -0.12065 -0.305054)
			(end -0.12065 -0.2794)
			(stroke
				(width 0.1)
				(type default)
			)
			(layer "F.Fab")
		)
		(fp_line
			(start -0.67945 -0.305054)
			(end -0.12065 -0.305054)
			(stroke
				(width 0.1)
				(type default)
			)
			(layer "F.Fab")
		)
		(fp_line
			(start 0.67945 -0.3048)
			(end 0.67945 0.3048)
			(stroke
				(width 0.1)
				(type default)
			)
			(layer "F.Fab")
		)
		(fp_line
			(start 0.12065 -0.3048)
			(end 0.67945 -0.3048)
			(stroke
				(width 0.1)
				(type default)
			)
			(layer "F.Fab")
		)
		(fp_line
			(start 0.12065 -0.2794)
			(end 0.12065 -0.3048)
			(stroke
				(width 0.1)
				(type default)
			)
			(layer "F.Fab")
		)
		(fp_line
			(start -0.12065 -0.2794)
			(end 0.12065 -0.2794)
			(stroke
				(width 0.1)
				(type default)
			)
			(layer "F.Fab")
		)
		(fp_line
			(start 0.120396 0.2794)
			(end -0.12065 0.2794)
			(stroke
				(width 0.1)
				(type default)
			)
			(layer "F.Fab")
		)
		(fp_line
			(start -0.12065 0.2794)
			(end -0.12065 0.3048)
			(stroke
				(width 0.1)
				(type default)
			)
			(layer "F.Fab")
		)
		(fp_line
			(start 0.67945 0.3048)
			(end 0.120396 0.3048)
			(stroke
				(width 0.1)
				(type default)
			)
			(layer "F.Fab")
		)
		(fp_line
			(start 0.120396 0.3048)
			(end 0.120396 0.2794)
			(stroke
				(width 0.1)
				(type default)
			)
			(layer "F.Fab")
		)
		(fp_line
			(start -0.12065 0.3048)
			(end -0.67945 0.3048)
			(stroke
				(width 0.1)
				(type default)
			)
			(layer "F.Fab")
		)
		(fp_line
			(start -0.67945 0.3048)
			(end -0.67945 -0.305054)
			(stroke
				(width 0.1)
				(type default)
			)
			(layer "F.Fab")
		)
		(pad "1" smd circle
			(at -0.40005 0 90)
			(size 0 0)
			(layers "F.Cu" "F.Mask" "F.Paste")
			(net "SW_PVDDCR_CPU1_P0_SW1_RC")
		)
		(pad "2" smd circle
			(at 0.40005 0 90)
			(size 0 0)
			(layers "F.Cu" "F.Mask" "F.Paste")
			(net "GND")
		)
	)
	(footprint ""
		(layer "F.Cu")
		(at 177.927 -133.568948 -90)
		(property "Reference" "R197"
			(at 0 0 270)
			(layer "F.SilkS")
			(hide yes)
			(effects
				(font
					(size 1.27 1.27)
				)
			)
		)
		(property "Value" ""
			(at 0 0 270)
			(layer "F.Fab")
			(effects
				(font
					(size 1.27 1.27)
				)
			)
		)
		(duplicate_pad_numbers_are_jumpers no)
		(fp_line
			(start -0.7874 0.4064)
			(end -0.7874 -0.4064)
			(stroke
				(width 0.1524)
				(type default)
			)
			(layer "F.SilkS")
		)
		(fp_line
			(start 0.7874 0.4064)
			(end -0.7874 0.4064)
			(stroke
				(width 0.1524)
				(type default)
			)
			(layer "F.SilkS")
		)
		(fp_line
			(start -0.7874 -0.4064)
			(end 0.7874 -0.4064)
			(stroke
				(width 0.1524)
				(type default)
			)
			(layer "F.SilkS")
		)
		(fp_line
			(start 0.7874 -0.4064)
			(end 0.7874 0.4064)
			(stroke
				(width 0.1524)
				(type default)
			)
			(layer "F.SilkS")
		)
		(fp_line
			(start -0.67945 0.3048)
			(end -0.67945 -0.305054)
			(stroke
				(width 0.1)
				(type default)
			)
			(layer "F.Fab")
		)
		(fp_line
			(start -0.12065 0.3048)
			(end -0.67945 0.3048)
			(stroke
				(width 0.1)
				(type default)
			)
			(layer "F.Fab")
		)
		(fp_line
			(start 0.120396 0.3048)
			(end 0.120396 0.2794)
			(stroke
				(width 0.1)
				(type default)
			)
			(layer "F.Fab")
		)
		(fp_line
			(start 0.67945 0.3048)
			(end 0.120396 0.3048)
			(stroke
				(width 0.1)
				(type default)
			)
			(layer "F.Fab")
		)
		(fp_line
			(start -0.12065 0.2794)
			(end -0.12065 0.3048)
			(stroke
				(width 0.1)
				(type default)
			)
			(layer "F.Fab")
		)
		(fp_line
			(start 0.120396 0.2794)
			(end -0.12065 0.2794)
			(stroke
				(width 0.1)
				(type default)
			)
			(layer "F.Fab")
		)
		(fp_line
			(start -0.12065 -0.2794)
			(end 0.12065 -0.2794)
			(stroke
				(width 0.1)
				(type default)
			)
			(layer "F.Fab")
		)
		(fp_line
			(start 0.12065 -0.2794)
			(end 0.12065 -0.3048)
			(stroke
				(width 0.1)
				(type default)
			)
			(layer "F.Fab")
		)
		(fp_line
			(start 0.12065 -0.3048)
			(end 0.67945 -0.3048)
			(stroke
				(width 0.1)
				(type default)
			)
			(layer "F.Fab")
		)
		(fp_line
			(start 0.67945 -0.3048)
			(end 0.67945 0.3048)
			(stroke
				(width 0.1)
				(type default)
			)
			(layer "F.Fab")
		)
		(fp_line
			(start -0.67945 -0.305054)
			(end -0.12065 -0.305054)
			(stroke
				(width 0.1)
				(type default)
			)
			(layer "F.Fab")
		)
		(fp_line
			(start -0.12065 -0.305054)
			(end -0.12065 -0.2794)
			(stroke
				(width 0.1)
				(type default)
			)
			(layer "F.Fab")
		)
		(pad "1" smd circle
			(at -0.40005 0 270)
			(size 0 0)
			(layers "F.Cu" "F.Mask" "F.Paste")
			(net "RST_CPU1_PERST0_N")
		)
		(pad "2" smd circle
			(at 0.40005 0 270)
			(size 0 0)
			(layers "F.Cu" "F.Mask" "F.Paste")
			(net "RST_CPU1_PERST0_R_N")
		)
	)
	(footprint ""
		(layer "F.Cu")
		(at 359.567988 -409.388818 90)
		(property "Reference" "R3033"
			(at 0 0 90)
			(layer "F.SilkS")
			(hide yes)
			(effects
				(font
					(size 1.27 1.27)
				)
			)
		)
		(property "Value" ""
			(at 0 0 90)
			(layer "F.Fab")
			(effects
				(font
					(size 1.27 1.27)
				)
			)
		)
		(duplicate_pad_numbers_are_jumpers no)
		(fp_line
			(start 0.7874 -0.4064)
			(end 0.7874 0.4064)
			(stroke
				(width 0.1524)
				(type default)
			)
			(layer "F.SilkS")
		)
		(fp_line
			(start -0.7874 -0.4064)
			(end 0.7874 -0.4064)
			(stroke
				(width 0.1524)
				(type default)
			)
			(layer "F.SilkS")
		)
		(fp_line
			(start 0.7874 0.4064)
			(end -0.7874 0.4064)
			(stroke
				(width 0.1524)
				(type default)
			)
			(layer "F.SilkS")
		)
		(fp_line
			(start -0.7874 0.4064)
			(end -0.7874 -0.4064)
			(stroke
				(width 0.1524)
				(type default)
			)
			(layer "F.SilkS")
		)
		(fp_line
			(start -0.12065 -0.305054)
			(end -0.12065 -0.2794)
			(stroke
				(width 0.1)
				(type default)
			)
			(layer "F.Fab")
		)
		(fp_line
			(start -0.67945 -0.305054)
			(end -0.12065 -0.305054)
			(stroke
				(width 0.1)
				(type default)
			)
			(layer "F.Fab")
		)
		(fp_line
			(start 0.67945 -0.3048)
			(end 0.67945 0.3048)
			(stroke
				(width 0.1)
				(type default)
			)
			(layer "F.Fab")
		)
		(fp_line
			(start 0.12065 -0.3048)
			(end 0.67945 -0.3048)
			(stroke
				(width 0.1)
				(type default)
			)
			(layer "F.Fab")
		)
		(fp_line
			(start 0.12065 -0.2794)
			(end 0.12065 -0.3048)
			(stroke
				(width 0.1)
				(type default)
			)
			(layer "F.Fab")
		)
		(fp_line
			(start -0.12065 -0.2794)
			(end 0.12065 -0.2794)
			(stroke
				(width 0.1)
				(type default)
			)
			(layer "F.Fab")
		)
		(fp_line
			(start 0.120396 0.2794)
			(end -0.12065 0.2794)
			(stroke
				(width 0.1)
				(type default)
			)
			(layer "F.Fab")
		)
		(fp_line
			(start -0.12065 0.2794)
			(end -0.12065 0.3048)
			(stroke
				(width 0.1)
				(type default)
			)
			(layer "F.Fab")
		)
		(fp_line
			(start 0.67945 0.3048)
			(end 0.120396 0.3048)
			(stroke
				(width 0.1)
				(type default)
			)
			(layer "F.Fab")
		)
		(fp_line
			(start 0.120396 0.3048)
			(end 0.120396 0.2794)
			(stroke
				(width 0.1)
				(type default)
			)
			(layer "F.Fab")
		)
		(fp_line
			(start -0.12065 0.3048)
			(end -0.67945 0.3048)
			(stroke
				(width 0.1)
				(type default)
			)
			(layer "F.Fab")
		)
		(fp_line
			(start -0.67945 0.3048)
			(end -0.67945 -0.305054)
			(stroke
				(width 0.1)
				(type default)
			)
			(layer "F.Fab")
		)
		(pad "1" smd circle
			(at -0.40005 0 90)
			(size 0 0)
			(layers "F.Cu" "F.Mask" "F.Paste")
			(net "UART_BMC_BIC_RX")
		)
		(pad "2" smd circle
			(at 0.40005 0 90)
			(size 0 0)
			(layers "F.Cu" "F.Mask" "F.Paste")
			(net "UART_BMC_BIC_R_RX")
		)
	)
)
